(kicad_pcb
	(version 20241229)
	(generator "pcbnew")
	(generator_version "9.0")
	(general
		(thickness 1.294)
		(legacy_teardrops no)
	)
	(paper "A3")
	(title_block
		(title "Kintex 410T devboard")
		(date "2024-04-03")
		(rev "1.1.2")
		(comment 9 "footprints 644-649 of 975")
	)
	(layers
		(0 "F.Cu" mixed)
		(4 "In1.Cu" power)
		(6 "In2.Cu" power)
		(8 "In3.Cu" mixed)
		(10 "In4.Cu" power)
		(12 "In5.Cu" mixed)
		(14 "In6.Cu" power)
		(16 "In7.Cu" mixed)
		(18 "In8.Cu" power)
		(2 "B.Cu" mixed)
		(9 "F.Adhes" user "F.Adhesive")
		(11 "B.Adhes" user "B.Adhesive")
		(13 "F.Paste" user)
		(15 "B.Paste" user)
		(5 "F.SilkS" user "F.Silkscreen")
		(7 "B.SilkS" user "B.Silkscreen")
		(1 "F.Mask" user)
		(3 "B.Mask" user)
		(17 "Dwgs.User" user "User.Drawings")
		(19 "Cmts.User" user "User.Comments")
		(21 "Eco1.User" user "User.Eco1")
		(23 "Eco2.User" user "User.Eco2")
		(25 "Edge.Cuts" user)
		(27 "Margin" user)
		(31 "F.CrtYd" user "F.Courtyard")
		(29 "B.CrtYd" user "B.Courtyard")
		(35 "F.Fab" user)
		(33 "B.Fab" user)
	)
	(footprint "antmicro-footprints:C_0201"
		(layer "B.Cu")
		(at 189.8 127.5 180)
		(descr "Capacitor SMD 0201")
		(tags "capacitor SMD 0201")
		(property "Reference" "C156"
			(at 0.5 -0.375 0)
			(layer "B.SilkS")
			(effects
				(font
					(size 0.7 0.7)
					(thickness 0.15)
				)
				(justify left bottom mirror)
			)
		)
		(property "Value" "C_100n_0201"
			(at 0 -1.4 0)
			(layer "B.Fab")
			(effects
				(font
					(size 0.7 0.7)
					(thickness 0.15)
				)
				(justify left bottom mirror)
			)
		)
		(property "Description" "SMD Multilayer Ceramic Capacitor, 0.1 µF, 6.3 V, 0201 [0603 Metric], ± 10%, X6S, CC Series"
			(at 0 0 180)
			(layer "F.Fab")
			(hide yes)
			(effects
				(font
					(size 1.27 1.27)
					(thickness 0.15)
				)
			)
		)
		(property "Author" "Antmicro"
			(at 379.6 255 0)
			(layer "B.Fab")
			(hide yes)
			(effects
				(font
					(size 1 1)
					(thickness 0.15)
				)
				(justify mirror)
			)
		)
		(property "Dielectric" ""
			(at 379.6 255 0)
			(layer "B.Fab")
			(hide yes)
			(effects
				(font
					(size 1 1)
					(thickness 0.15)
				)
				(justify mirror)
			)
		)
		(property "License" "Apache-2.0"
			(at 379.6 255 0)
			(layer "B.Fab")
			(hide yes)
			(effects
				(font
					(size 1 1)
					(thickness 0.15)
				)
				(justify mirror)
			)
		)
		(property "MPN" "CC0201KRX6S5BB104"
			(at 379.6 255 0)
			(layer "B.Fab")
			(hide yes)
			(effects
				(font
					(size 1 1)
					(thickness 0.15)
				)
				(justify mirror)
			)
		)
		(property "Manufacturer" "YAGEO"
			(at 379.6 255 0)
			(layer "B.Fab")
			(hide yes)
			(effects
				(font
					(size 1 1)
					(thickness 0.15)
				)
				(justify mirror)
			)
		)
		(property "Val" "100n"
			(at 379.6 255 0)
			(layer "B.Fab")
			(hide yes)
			(effects
				(font
					(size 1 1)
					(thickness 0.15)
				)
				(justify mirror)
			)
		)
		(property "Voltage" ""
			(at 379.6 255 0)
			(layer "B.Fab")
			(hide yes)
			(effects
				(font
					(size 1 1)
					(thickness 0.15)
				)
				(justify mirror)
			)
		)
		(sheetname "FPGA supply")
		(sheetfile "fpga-supply.kicad_sch")
		(attr smd)
		(fp_rect
			(start -0.7 0.35)
			(end 0.7 -0.35)
			(stroke
				(width 0.05)
				(type default)
			)
			(fill no)
			(layer "B.CrtYd")
		)
		(fp_rect
			(start 0.3 -0.15)
			(end -0.301 0.149)
			(stroke
				(width 0.15)
				(type solid)
			)
			(fill no)
			(layer "B.Fab")
		)
		(pad "" smd roundrect
			(at -0.349 0.002 180)
			(size 0.318 0.36)
			(layers "B.Paste")
			(roundrect_rratio 0.25)
		)
		(pad "" smd roundrect
			(at 0.341 0.002 180)
			(size 0.318 0.36)
			(layers "B.Paste")
			(roundrect_rratio 0.25)
		)
		(pad "1" smd roundrect
			(at -0.321 0.002 180)
			(size 0.46 0.4)
			(layers "B.Cu" "B.Mask")
			(roundrect_rratio 0.25)
			(net 1 "GND")
			(pintype "passive")
		)
		(pad "2" smd roundrect
			(at 0.32 0.002 180)
			(size 0.46 0.4)
			(layers "B.Cu" "B.Mask")
			(roundrect_rratio 0.25)
			(net 8 "+1V2_MGTAVTT")
			(pintype "passive")
		)
	)
	(footprint "antmicro-footprints:C_0603_1608Metric"
		(layer "B.Cu")
		(at 212.85 130 180)
		(descr "Capacitor SMD 0603")
		(tags "capacitor 0603")
		(property "Reference" "C4"
			(at -0.21 -1.42 0)
			(layer "B.SilkS")
			(effects
				(font
					(size 0.7 0.7)
					(thickness 0.15)
				)
				(justify left bottom mirror)
			)
		)
		(property "Value" "C_47u_0603"
			(at 0 -1.6 0)
			(layer "B.Fab")
			(effects
				(font
					(size 0.7 0.7)
					(thickness 0.15)
				)
				(justify left bottom mirror)
			)
		)
		(property "Description" "SMD Multilayer Ceramic Capacitor, 47 µF, 6.3 V, 0603 [1608 Metric], ± 20%, X5R, GRM Series"
			(at 0 0 180)
			(layer "F.Fab")
			(hide yes)
			(effects
				(font
					(size 1.27 1.27)
					(thickness 0.15)
				)
			)
		)
		(property "Author" "Antmicro"
			(at 425.7 260 0)
			(layer "B.Fab")
			(hide yes)
			(effects
				(font
					(size 1 1)
					(thickness 0.15)
				)
				(justify mirror)
			)
		)
		(property "Dielectric" ""
			(at 425.7 260 0)
			(layer "B.Fab")
			(hide yes)
			(effects
				(font
					(size 1 1)
					(thickness 0.15)
				)
				(justify mirror)
			)
		)
		(property "License" "Apache-2.0"
			(at 425.7 260 0)
			(layer "B.Fab")
			(hide yes)
			(effects
				(font
					(size 1 1)
					(thickness 0.15)
				)
				(justify mirror)
			)
		)
		(property "MPN" "GRM188R60J476ME15D"
			(at 425.7 260 0)
			(layer "B.Fab")
			(hide yes)
			(effects
				(font
					(size 1 1)
					(thickness 0.15)
				)
				(justify mirror)
			)
		)
		(property "Manufacturer" "Murata"
			(at 425.7 260 0)
			(layer "B.Fab")
			(hide yes)
			(effects
				(font
					(size 1 1)
					(thickness 0.15)
				)
				(justify mirror)
			)
		)
		(property "Val" "47u"
			(at 425.7 260 0)
			(layer "B.Fab")
			(hide yes)
			(effects
				(font
					(size 1 1)
					(thickness 0.15)
				)
				(justify mirror)
			)
		)
		(property "Voltage" ""
			(at 425.7 260 0)
			(layer "B.Fab")
			(hide yes)
			(effects
				(font
					(size 1 1)
					(thickness 0.15)
				)
				(justify mirror)
			)
		)
		(sheetname "FPGA Bank 12 & 13")
		(sheetfile "fpga-bank-12-13.kicad_sch")
		(attr smd)
		(fp_line
			(start -0.15 0.4)
			(end 0.15 0.4)
			(stroke
				(width 0.15)
				(type solid)
			)
			(layer "B.SilkS")
		)
		(fp_line
			(start -0.15 -0.4)
			(end 0.15 -0.4)
			(stroke
				(width 0.15)
				(type solid)
			)
			(layer "B.SilkS")
		)
		(fp_rect
			(start -1.25 0.65)
			(end 1.25 -0.65)
			(stroke
				(width 0.05)
				(type solid)
			)
			(fill no)
			(layer "B.CrtYd")
		)
		(fp_rect
			(start -0.8 0.4)
			(end 0.8 -0.4)
			(stroke
				(width 0.15)
				(type solid)
			)
			(fill no)
			(layer "B.Fab")
		)
		(pad "1" smd roundrect
			(at -0.7 0 180)
			(size 0.8 1)
			(layers "B.Cu" "B.Mask" "B.Paste")
			(roundrect_rratio 0.2)
			(net 1 "GND")
			(pintype "passive")
		)
		(pad "2" smd roundrect
			(at 0.7 0 180)
			(size 0.8 1)
			(layers "B.Cu" "B.Mask" "B.Paste")
			(roundrect_rratio 0.2)
			(net 24 "+3V3")
			(pintype "passive")
		)
	)
	(footprint "antmicro-footprints:R_0402_1005Metric"
		(layer "B.Cu")
		(at 246.351 130.1 90)
		(descr "Resistor SMD 0402")
		(tags "resistor SMD 0402")
		(property "Reference" "R90"
			(at -0.8 0.374 270)
			(layer "B.SilkS")
			(effects
				(font
					(size 0.7 0.7)
					(thickness 0.15)
				)
				(justify left bottom mirror)
			)
		)
		(property "Value" "R_10k_0402"
			(at 0 -1.4 270)
			(layer "B.Fab")
			(effects
				(font
					(size 0.7 0.7)
					(thickness 0.15)
				)
				(justify left bottom mirror)
			)
		)
		(property "Description" "SMD Chip Resistor, 10 kohm, ± 1%, 62.5 mW, 0402 [1005 Metric], Thick Film, General Purpose"
			(at 0 0 90)
			(layer "F.Fab")
			(hide yes)
			(effects
				(font
					(size 1.27 1.27)
					(thickness 0.15)
				)
			)
		)
		(property "Author" "Antmicro"
			(at 376.451 -116.251 0)
			(layer "B.Fab")
			(hide yes)
			(effects
				(font
					(size 1 1)
					(thickness 0.15)
				)
				(justify mirror)
			)
		)
		(property "License" "Apache-2.0"
			(at 376.451 -116.251 0)
			(layer "B.Fab")
			(hide yes)
			(effects
				(font
					(size 1 1)
					(thickness 0.15)
				)
				(justify mirror)
			)
		)
		(property "MPN" "CR0402-FX-1002GLF"
			(at 376.451 -116.251 0)
			(layer "B.Fab")
			(hide yes)
			(effects
				(font
					(size 1 1)
					(thickness 0.15)
				)
				(justify mirror)
			)
		)
		(property "Manufacturer" "Bourns"
			(at 376.451 -116.251 0)
			(layer "B.Fab")
			(hide yes)
			(effects
				(font
					(size 1 1)
					(thickness 0.15)
				)
				(justify mirror)
			)
		)
		(property "Tolerance" "1%"
			(at 376.451 -116.251 0)
			(layer "B.Fab")
			(hide yes)
			(effects
				(font
					(size 1 1)
					(thickness 0.15)
				)
				(justify mirror)
			)
		)
		(property "Val" "10k"
			(at 376.451 -116.251 0)
			(layer "B.Fab")
			(hide yes)
			(effects
				(font
					(size 1 1)
					(thickness 0.15)
				)
				(justify mirror)
			)
		)
		(sheetname "SPI Flash + SD Card")
		(sheetfile "spi-flash.kicad_sch")
		(attr smd)
		(fp_rect
			(start -0.925 0.47)
			(end 0.925 -0.47)
			(stroke
				(width 0.05)
				(type default)
			)
			(fill no)
			(layer "B.CrtYd")
		)
		(fp_rect
			(start -0.5 0.25)
			(end 0.5 -0.25)
			(stroke
				(width 0.15)
				(type solid)
			)
			(fill no)
			(layer "B.Fab")
		)
		(pad "1" smd roundrect
			(at -0.48 0 90)
			(size 0.59 0.64)
			(layers "B.Cu" "B.Mask" "B.Paste")
			(roundrect_rratio 0.25)
			(net 395 "/FPGA Bank 33 & 34/SD_CARD.DAT0")
			(pintype "passive")
		)
		(pad "2" smd roundrect
			(at 0.48 0 90)
			(size 0.59 0.64)
			(layers "B.Cu" "B.Mask" "B.Paste")
			(roundrect_rratio 0.25)
			(net 24 "+3V3")
			(pintype "passive")
		)
	)
	(footprint "antmicro-footprints:QFN-2L_1.6x1x0.55mm"
		(layer "B.Cu")
		(at 264.75 84 90)
		(property "Reference" "D34"
			(at -2.1 -0.85 90)
			(layer "B.SilkS")
			(effects
				(font
					(size 0.7 0.7)
					(thickness 0.15)
				)
				(justify right bottom mirror)
			)
		)
		(property "Value" "ESDA25P35-1U1M"
			(at 0 -1.7 90)
			(layer "B.Fab")
			(effects
				(font
					(size 0.7 0.7)
					(thickness 0.15)
				)
				(justify right bottom mirror)
			)
		)
		(property "Description" "Unidirectional TVS, 30 kV, QFN-2L, 22 V, 195 pF"
			(at 0 0 90)
			(layer "F.Fab")
			(hide yes)
			(effects
				(font
					(size 1.27 1.27)
					(thickness 0.15)
				)
			)
		)
		(property "Author" "Antmicro"
			(at 348.75 -180.75 0)
			(layer "B.Fab")
			(hide yes)
			(effects
				(font
					(size 1 1)
					(thickness 0.15)
				)
				(justify mirror)
			)
		)
		(property "License" "Apache-2.0"
			(at 348.75 -180.75 0)
			(layer "B.Fab")
			(hide yes)
			(effects
				(font
					(size 1 1)
					(thickness 0.15)
				)
				(justify mirror)
			)
		)
		(property "MPN" "ESDA25P35-1U1M"
			(at 348.75 -180.75 0)
			(layer "B.Fab")
			(hide yes)
			(effects
				(font
					(size 1 1)
					(thickness 0.15)
				)
				(justify mirror)
			)
		)
		(property "Manufacturer" "STMicroelectronics"
			(at 348.75 -180.75 0)
			(layer "B.Fab")
			(hide yes)
			(effects
				(font
					(size 1 1)
					(thickness 0.15)
				)
				(justify mirror)
			)
		)
		(property "Public" "False"
			(at 348.75 -180.75 0)
			(layer "B.Fab")
			(hide yes)
			(effects
				(font
					(size 1 1)
					(thickness 0.15)
				)
				(justify mirror)
			)
		)
		(sheetname "User GPIO + LED + button + DIP switch")
		(sheetfile "user-gpio.kicad_sch")
		(attr smd)
		(fp_line
			(start 0.27 -0.3)
			(end -0.27 -0.3)
			(stroke
				(width 0.15)
				(type solid)
			)
			(layer "B.SilkS")
		)
		(fp_line
			(start 0.27 0.3)
			(end -0.27 0.3)
			(stroke
				(width 0.15)
				(type solid)
			)
			(layer "B.SilkS")
		)
		(fp_line
			(start -1.2 0.4)
			(end -1.2 -0.4)
			(stroke
				(width 0.15)
				(type solid)
			)
			(layer "B.SilkS")
		)
		(fp_rect
			(start 1.25 -0.65)
			(end -1.25 0.65)
			(stroke
				(width 0.05)
				(type solid)
			)
			(fill no)
			(layer "B.CrtYd")
		)
		(fp_line
			(start 0.201 -0.2)
			(end 0.201 0)
			(stroke
				(width 0.15)
				(type solid)
			)
			(layer "B.Fab")
		)
		(fp_line
			(start -0.199 -0.2)
			(end -0.199 -0.1)
			(stroke
				(width 0.15)
				(type solid)
			)
			(layer "B.Fab")
		)
		(fp_line
			(start 0.599 0)
			(end 0.201 0)
			(stroke
				(width 0.15)
				(type solid)
			)
			(layer "B.Fab")
		)
		(fp_line
			(start 0.201 0)
			(end 0.201 0.202)
			(stroke
				(width 0.15)
				(type solid)
			)
			(layer "B.Fab")
		)
		(fp_line
			(start -0.101 0)
			(end 0.201 -0.2)
			(stroke
				(width 0.15)
				(type solid)
			)
			(layer "B.Fab")
		)
		(fp_line
			(start -0.199 0)
			(end -0.597 0)
			(stroke
				(width 0.15)
				(type solid)
			)
			(layer "B.Fab")
		)
		(fp_line
			(start 0.201 0.202)
			(end -0.101 0)
			(stroke
				(width 0.15)
				(type solid)
			)
			(layer "B.Fab")
		)
		(fp_line
			(start -0.199 0.202)
			(end -0.199 -0.1)
			(stroke
				(width 0.15)
				(type solid)
			)
			(layer "B.Fab")
		)
		(fp_rect
			(start 0.848 -0.4)
			(end -0.85 0.402)
			(stroke
				(width 0.15)
				(type solid)
			)
			(fill no)
			(layer "B.Fab")
		)
		(pad "1" smd roundrect
			(at -0.7 0 270)
			(size 0.8 1)
			(layers "B.Cu" "B.Mask" "B.Paste")
			(roundrect_rratio 0.2)
			(net 13 "/USER_IO.BUTTON1")
			(pinfunction "C")
			(pintype "passive")
		)
		(pad "2" smd roundrect
			(at 0.7 0 270)
			(size 0.8 1)
			(layers "B.Cu" "B.Mask" "B.Paste")
			(roundrect_rratio 0.2)
			(net 1 "GND")
			(pinfunction "A")
			(pintype "passive")
		)
	)
	(footprint "antmicro-footprints:R_0402_1005Metric"
		(layer "B.Cu")
		(at 197.6 177.8 180)
		(descr "Resistor SMD 0402")
		(tags "resistor SMD 0402")
		(property "Reference" "R62"
			(at -1.025 0.5 0)
			(layer "B.SilkS")
			(effects
				(font
					(size 0.7 0.7)
					(thickness 0.15)
				)
				(justify left bottom mirror)
			)
		)
		(property "Value" "R_0R_0402"
			(at 0 -1.4 0)
			(layer "B.Fab")
			(effects
				(font
					(size 0.7 0.7)
					(thickness 0.15)
				)
				(justify left bottom mirror)
			)
		)
		(property "Description" "SMD Chip Resistor, Jumper, 0 ohm, 100 mW, 0402 [1005 Metric], Thick Film, General Purpose"
			(at 0 0 180)
			(layer "F.Fab")
			(hide yes)
			(effects
				(font
					(size 1.27 1.27)
					(thickness 0.15)
				)
			)
		)
		(property "Author" "Antmicro"
			(at 395.2 355.6 0)
			(layer "B.Fab")
			(hide yes)
			(effects
				(font
					(size 1 1)
					(thickness 0.15)
				)
				(justify mirror)
			)
		)
		(property "Current" "1A"
			(at 395.2 355.6 0)
			(layer "B.Fab")
			(hide yes)
			(effects
				(font
					(size 1 1)
					(thickness 0.15)
				)
				(justify mirror)
			)
		)
		(property "License" "Apache-2.0"
			(at 395.2 355.6 0)
			(layer "B.Fab")
			(hide yes)
			(effects
				(font
					(size 1 1)
					(thickness 0.15)
				)
				(justify mirror)
			)
		)
		(property "MPN" "ERJ2GE0R00X"
			(at 395.2 355.6 0)
			(layer "B.Fab")
			(hide yes)
			(effects
				(font
					(size 1 1)
					(thickness 0.15)
				)
				(justify mirror)
			)
		)
		(property "Manufacturer" "Panasonic"
			(at 395.2 355.6 0)
			(layer "B.Fab")
			(hide yes)
			(effects
				(font
					(size 1 1)
					(thickness 0.15)
				)
				(justify mirror)
			)
		)
		(property "Tolerance" ""
			(at 395.2 355.6 0)
			(layer "B.Fab")
			(hide yes)
			(effects
				(font
					(size 1 1)
					(thickness 0.15)
				)
				(justify mirror)
			)
		)
		(property "Val" "0R"
			(at 395.2 355.6 0)
			(layer "B.Fab")
			(hide yes)
			(effects
				(font
					(size 1 1)
					(thickness 0.15)
				)
				(justify mirror)
			)
		)
		(sheetname "Power supply")
		(sheetfile "power-supply.kicad_sch")
		(attr smd)
		(fp_rect
			(start -0.925 0.47)
			(end 0.925 -0.47)
			(stroke
				(width 0.05)
				(type default)
			)
			(fill no)
			(layer "B.CrtYd")
		)
		(fp_rect
			(start -0.5 0.25)
			(end 0.5 -0.25)
			(stroke
				(width 0.15)
				(type solid)
			)
			(fill no)
			(layer "B.Fab")
		)
		(pad "1" smd roundrect
			(at -0.48 0 180)
			(size 0.59 0.64)
			(layers "B.Cu" "B.Mask" "B.Paste")
			(roundrect_rratio 0.25)
			(net 365 "Net-(U8-TRIM)")
			(pintype "passive")
		)
		(pad "2" smd roundrect
			(at 0.48 0 180)
			(size 0.59 0.64)
			(layers "B.Cu" "B.Mask" "B.Paste")
			(roundrect_rratio 0.25)
			(net 891 "unconnected-(R62-Pad2)")
			(pintype "passive+no_connect")
		)
	)
	(footprint "antmicro-footprints:R_Array_4x0201_Panasonic_EXB18V"
		(layer "B.Cu")
		(at 249.901 149.15)
		(property "Reference" "R30"
			(at 1.074 -0.75 0)
			(layer "B.SilkS")
			(effects
				(font
					(size 0.7 0.7)
					(thickness 0.15)
				)
				(justify left bottom mirror)
			)
		)
		(property "Value" "R_4x33R_0201_array"
			(at -1.1 -1.8 0)
			(layer "B.Fab")
			(effects
				(font
					(size 0.7 0.7)
					(thickness 0.15)
				)
				(justify right bottom mirror)
			)
		)
		(property "Description" "Fixed Network Resistor, 33 ohm, Isolated, 4 Resistors, 0502 [1406 Metric], Flat, ± 5%"
			(at 0 0 0)
			(layer "F.Fab")
			(hide yes)
			(effects
				(font
					(size 1.27 1.27)
					(thickness 0.15)
				)
			)
		)
		(property "Author" "Antmicro"
			(at 0 0 0)
			(layer "B.Fab")
			(hide yes)
			(effects
				(font
					(size 1 1)
					(thickness 0.15)
				)
				(justify mirror)
			)
		)
		(property "License" "Apache-2.0"
			(at 0 0 0)
			(layer "B.Fab")
			(hide yes)
			(effects
				(font
					(size 1 1)
					(thickness 0.15)
				)
				(justify mirror)
			)
		)
		(property "MPN" "EXB-18V330JX"
			(at 0 0 0)
			(layer "B.Fab")
			(hide yes)
			(effects
				(font
					(size 1 1)
					(thickness 0.15)
				)
				(justify mirror)
			)
		)
		(property "Manufacturer" "Panasonic"
			(at 0 0 0)
			(layer "B.Fab")
			(hide yes)
			(effects
				(font
					(size 1 1)
					(thickness 0.15)
				)
				(justify mirror)
			)
		)
		(property "Val" "R_4x33R_0201"
			(at 0 0 0)
			(layer "B.Fab")
			(hide yes)
			(effects
				(font
					(size 1 1)
					(thickness 0.15)
				)
				(justify mirror)
			)
		)
		(sheetname "Supervisior MCU")
		(sheetfile "supervisor-mcu.kicad_sch")
		(attr smd)
		(fp_line
			(start -0.8 0.45)
			(end -0.8 -0.45)
			(stroke
				(width 0.12)
				(type solid)
			)
			(layer "B.SilkS")
		)
		(fp_line
			(start 0.8 0.45)
			(end 0.8 -0.45)
			(stroke
				(width 0.12)
				(type solid)
			)
			(layer "B.SilkS")
		)
		(fp_rect
			(start -0.898 0.66)
			(end 0.898 -0.65)
			(stroke
				(width 0.05)
				(type solid)
			)
			(fill no)
			(layer "B.CrtYd")
		)
		(pad "1" smd roundrect
			(at -0.6 -0.298)
			(size 0.2 0.4)
			(layers "B.Cu" "B.Mask" "B.Paste")
			(roundrect_rratio 0.25)
			(net 1315 "/SUP_MCU.DONE")
			(pinfunction "R1.1")
			(pintype "passive")
		)
		(pad "2" smd roundrect
			(at -0.202 -0.298)
			(size 0.2 0.4)
			(layers "B.Cu" "B.Mask" "B.Paste")
			(roundrect_rratio 0.25)
			(net 1317 "/SUP_MCU.PROGRAMB")
			(pinfunction "R2.1")
			(pintype "passive")
		)
		(pad "3" smd roundrect
			(at 0.2 -0.298)
			(size 0.2 0.4)
			(layers "B.Cu" "B.Mask" "B.Paste")
			(roundrect_rratio 0.25)
			(net 1326 "/SUP_MCU.FPGA_MISO")
			(pinfunction "R3.1")
			(pintype "passive")
		)
		(pad "4" smd roundrect
			(at 0.598 -0.298)
			(size 0.2 0.4)
			(layers "B.Cu" "B.Mask" "B.Paste")
			(roundrect_rratio 0.25)
			(net 1377 "/SUP_MCU.SPARE0")
			(pinfunction "R4.1")
			(pintype "passive")
		)
		(pad "5" smd roundrect
			(at 0.598 0.3)
			(size 0.2 0.4)
			(layers "B.Cu" "B.Mask" "B.Paste")
			(roundrect_rratio 0.25)
			(net 1114 "/Supervisior MCU/USB_SPARE0")
			(pinfunction "R4.2")
			(pintype "passive")
		)
		(pad "6" smd roundrect
			(at 0.2 0.3)
			(size 0.2 0.4)
			(layers "B.Cu" "B.Mask" "B.Paste")
			(roundrect_rratio 0.25)
			(net 975 "/Supervisior MCU/FPGA_CIPO")
			(pinfunction "R3.2")
			(pintype "passive")
		)
		(pad "7" smd roundrect
			(at -0.202 0.3)
			(size 0.2 0.4)
			(layers "B.Cu" "B.Mask" "B.Paste")
			(roundrect_rratio 0.25)
			(net 1054 "/Supervisior MCU/CFG_PROGRAMB")
			(pinfunction "R2.2")
			(pintype "passive")
		)
		(pad "8" smd roundrect
			(at -0.6 0.3)
			(size 0.2 0.4)
			(layers "B.Cu" "B.Mask" "B.Paste")
			(roundrect_rratio 0.25)
			(net 250 "/Supervisior MCU/CFG_DONE")
			(pinfunction "R1.2")
			(pintype "passive")
		)
	)
)
